(kicad_pcb
	(version 20260206)
	(generator "pcbnew")
	(generator_version "10.0")
	(general
		(thickness 1.6)
		(legacy_teardrops no)
	)
	(paper "A4")
	(title_block
		(title "03242023_DA0F0TMBIJ0_F0T_Motherboard_J_brd_V01_OCP.brd")
		(comment 1 "Grand Teton / footprints 2939-2944 of 6105")
	)
	(layers
		(0 "F.Cu" signal "TOP")
		(4 "In1.Cu" signal "GND")
		(6 "In2.Cu" signal "IN1")
		(8 "In3.Cu" signal "GND1")
		(10 "In4.Cu" signal "IN2")
		(12 "In5.Cu" signal "GND2")
		(14 "In6.Cu" signal "IN3")
		(16 "In7.Cu" signal "GND3")
		(18 "In8.Cu" signal "VCC")
		(20 "In9.Cu" signal "VCC1")
		(22 "In10.Cu" signal "GND4")
		(24 "In11.Cu" signal "IN4")
		(26 "In12.Cu" signal "GND5")
		(28 "In13.Cu" signal "IN5")
		(30 "In14.Cu" signal "GND6")
		(32 "In15.Cu" signal "IN6")
		(34 "In16.Cu" signal "GND7")
		(2 "B.Cu" signal "BOTTOM")
		(9 "F.Adhes" user "F.Adhesive")
		(11 "B.Adhes" user "B.Adhesive")
		(13 "F.Paste" user "Package Geometry/Pastemask Top")
		(15 "B.Paste" user "Package Geometry/Pastemask Bottom")
		(5 "F.SilkS" user "Ref Des/Silkscreen Top")
		(7 "B.SilkS" user "Ref Des/Silkscreen Bottom")
		(1 "F.Mask" user "Board Geometry/Soldermask Top")
		(3 "B.Mask" user "Board Geometry/Soldermask Bottom")
		(17 "Dwgs.User" user "User.Drawings")
		(19 "Cmts.User" user "User.Comments")
		(21 "Eco1.User" user "User.Eco1")
		(23 "Eco2.User" user "User.Eco2")
		(25 "Edge.Cuts" user "Board Geometry/Outline")
		(27 "Margin" user)
		(31 "F.CrtYd" user "Package Geometry/Place Bound Top")
		(29 "B.CrtYd" user "Package Geometry/Place Bound Bottom")
		(35 "F.Fab" user "Ref Des/Assembly Top")
		(33 "B.Fab" user "Ref Des/Assembly Bottom")
	)
	(footprint ""
		(layer "F.Cu")
		(at 353.235514 -255.053846 90)
		(property "Reference" "C986"
			(at 0 0 90)
			(layer "F.SilkS")
			(hide yes)
			(effects
				(font
					(size 1.27 1.27)
				)
			)
		)
		(property "Value" ""
			(at 0 0 90)
			(layer "F.Fab")
			(effects
				(font
					(size 1.27 1.27)
				)
			)
		)
		(duplicate_pad_numbers_are_jumpers no)
		(fp_line
			(start 0.7874 -0.4064)
			(end 0.7874 0.4064)
			(stroke
				(width 0.1524)
				(type default)
			)
			(layer "F.SilkS")
		)
		(fp_line
			(start -0.7874 -0.4064)
			(end 0.7874 -0.4064)
			(stroke
				(width 0.1524)
				(type default)
			)
			(layer "F.SilkS")
		)
		(fp_line
			(start 0.7874 0.4064)
			(end -0.7874 0.4064)
			(stroke
				(width 0.1524)
				(type default)
			)
			(layer "F.SilkS")
		)
		(fp_line
			(start -0.7874 0.4064)
			(end -0.7874 -0.4064)
			(stroke
				(width 0.1524)
				(type default)
			)
			(layer "F.SilkS")
		)
		(fp_line
			(start -0.12065 -0.305054)
			(end -0.12065 -0.2794)
			(stroke
				(width 0.1)
				(type default)
			)
			(layer "F.Fab")
		)
		(fp_line
			(start -0.67945 -0.305054)
			(end -0.12065 -0.305054)
			(stroke
				(width 0.1)
				(type default)
			)
			(layer "F.Fab")
		)
		(fp_line
			(start 0.67945 -0.3048)
			(end 0.67945 0.3048)
			(stroke
				(width 0.1)
				(type default)
			)
			(layer "F.Fab")
		)
		(fp_line
			(start 0.12065 -0.3048)
			(end 0.67945 -0.3048)
			(stroke
				(width 0.1)
				(type default)
			)
			(layer "F.Fab")
		)
		(fp_line
			(start 0.12065 -0.2794)
			(end 0.12065 -0.3048)
			(stroke
				(width 0.1)
				(type default)
			)
			(layer "F.Fab")
		)
		(fp_line
			(start -0.12065 -0.2794)
			(end 0.12065 -0.2794)
			(stroke
				(width 0.1)
				(type default)
			)
			(layer "F.Fab")
		)
		(fp_line
			(start 0.120396 0.2794)
			(end -0.12065 0.2794)
			(stroke
				(width 0.1)
				(type default)
			)
			(layer "F.Fab")
		)
		(fp_line
			(start -0.12065 0.2794)
			(end -0.12065 0.3048)
			(stroke
				(width 0.1)
				(type default)
			)
			(layer "F.Fab")
		)
		(fp_line
			(start 0.67945 0.3048)
			(end 0.120396 0.3048)
			(stroke
				(width 0.1)
				(type default)
			)
			(layer "F.Fab")
		)
		(fp_line
			(start 0.120396 0.3048)
			(end 0.120396 0.2794)
			(stroke
				(width 0.1)
				(type default)
			)
			(layer "F.Fab")
		)
		(fp_line
			(start -0.12065 0.3048)
			(end -0.67945 0.3048)
			(stroke
				(width 0.1)
				(type default)
			)
			(layer "F.Fab")
		)
		(fp_line
			(start -0.67945 0.3048)
			(end -0.67945 -0.305054)
			(stroke
				(width 0.1)
				(type default)
			)
			(layer "F.Fab")
		)
		(pad "1" smd circle
			(at -0.40005 0 90)
			(size 0 0)
			(layers "F.Cu" "F.Mask" "F.Paste")
			(net "PVCCIN_CPU0")
		)
		(pad "2" smd circle
			(at 0.40005 0 90)
			(size 0 0)
			(layers "F.Cu" "F.Mask" "F.Paste")
			(net "GND")
		)
	)
	(footprint ""
		(layer "F.Cu")
		(at 364.50143 -255.053846 90)
		(property "Reference" "C1000"
			(at 0 0 90)
			(layer "F.SilkS")
			(hide yes)
			(effects
				(font
					(size 1.27 1.27)
				)
			)
		)
		(property "Value" ""
			(at 0 0 90)
			(layer "F.Fab")
			(effects
				(font
					(size 1.27 1.27)
				)
			)
		)
		(duplicate_pad_numbers_are_jumpers no)
		(fp_line
			(start 0.7874 -0.4064)
			(end 0.7874 0.4064)
			(stroke
				(width 0.1524)
				(type default)
			)
			(layer "F.SilkS")
		)
		(fp_line
			(start -0.7874 -0.4064)
			(end 0.7874 -0.4064)
			(stroke
				(width 0.1524)
				(type default)
			)
			(layer "F.SilkS")
		)
		(fp_line
			(start 0.7874 0.4064)
			(end -0.7874 0.4064)
			(stroke
				(width 0.1524)
				(type default)
			)
			(layer "F.SilkS")
		)
		(fp_line
			(start -0.7874 0.4064)
			(end -0.7874 -0.4064)
			(stroke
				(width 0.1524)
				(type default)
			)
			(layer "F.SilkS")
		)
		(fp_line
			(start -0.12065 -0.305054)
			(end -0.12065 -0.2794)
			(stroke
				(width 0.1)
				(type default)
			)
			(layer "F.Fab")
		)
		(fp_line
			(start -0.67945 -0.305054)
			(end -0.12065 -0.305054)
			(stroke
				(width 0.1)
				(type default)
			)
			(layer "F.Fab")
		)
		(fp_line
			(start 0.67945 -0.3048)
			(end 0.67945 0.3048)
			(stroke
				(width 0.1)
				(type default)
			)
			(layer "F.Fab")
		)
		(fp_line
			(start 0.12065 -0.3048)
			(end 0.67945 -0.3048)
			(stroke
				(width 0.1)
				(type default)
			)
			(layer "F.Fab")
		)
		(fp_line
			(start 0.12065 -0.2794)
			(end 0.12065 -0.3048)
			(stroke
				(width 0.1)
				(type default)
			)
			(layer "F.Fab")
		)
		(fp_line
			(start -0.12065 -0.2794)
			(end 0.12065 -0.2794)
			(stroke
				(width 0.1)
				(type default)
			)
			(layer "F.Fab")
		)
		(fp_line
			(start 0.120396 0.2794)
			(end -0.12065 0.2794)
			(stroke
				(width 0.1)
				(type default)
			)
			(layer "F.Fab")
		)
		(fp_line
			(start -0.12065 0.2794)
			(end -0.12065 0.3048)
			(stroke
				(width 0.1)
				(type default)
			)
			(layer "F.Fab")
		)
		(fp_line
			(start 0.67945 0.3048)
			(end 0.120396 0.3048)
			(stroke
				(width 0.1)
				(type default)
			)
			(layer "F.Fab")
		)
		(fp_line
			(start 0.120396 0.3048)
			(end 0.120396 0.2794)
			(stroke
				(width 0.1)
				(type default)
			)
			(layer "F.Fab")
		)
		(fp_line
			(start -0.12065 0.3048)
			(end -0.67945 0.3048)
			(stroke
				(width 0.1)
				(type default)
			)
			(layer "F.Fab")
		)
		(fp_line
			(start -0.67945 0.3048)
			(end -0.67945 -0.305054)
			(stroke
				(width 0.1)
				(type default)
			)
			(layer "F.Fab")
		)
		(pad "1" smd circle
			(at -0.40005 0 90)
			(size 0 0)
			(layers "F.Cu" "F.Mask" "F.Paste")
			(net "PVCCIN_CPU0")
		)
		(pad "2" smd circle
			(at 0.40005 0 90)
			(size 0 0)
			(layers "F.Cu" "F.Mask" "F.Paste")
			(net "GND")
		)
	)
	(footprint ""
		(layer "F.Cu")
		(at 368.127788 -338.86013)
		(property "Reference" "PR144"
			(at 0 0 0)
			(layer "F.SilkS")
			(hide yes)
			(effects
				(font
					(size 1.27 1.27)
				)
			)
		)
		(property "Value" ""
			(at 0 0 0)
			(layer "F.Fab")
			(effects
				(font
					(size 1.27 1.27)
				)
			)
		)
		(duplicate_pad_numbers_are_jumpers no)
		(fp_line
			(start -0.7874 -0.4064)
			(end 0.7874 -0.4064)
			(stroke
				(width 0.1524)
				(type default)
			)
			(layer "F.SilkS")
		)
		(fp_line
			(start -0.7874 0.4064)
			(end -0.7874 -0.4064)
			(stroke
				(width 0.1524)
				(type default)
			)
			(layer "F.SilkS")
		)
		(fp_line
			(start 0.7874 -0.4064)
			(end 0.7874 0.4064)
			(stroke
				(width 0.1524)
				(type default)
			)
			(layer "F.SilkS")
		)
		(fp_line
			(start 0.7874 0.4064)
			(end -0.7874 0.4064)
			(stroke
				(width 0.1524)
				(type default)
			)
			(layer "F.SilkS")
		)
		(fp_line
			(start -0.67945 -0.305054)
			(end -0.12065 -0.305054)
			(stroke
				(width 0.1)
				(type default)
			)
			(layer "F.Fab")
		)
		(fp_line
			(start -0.67945 0.3048)
			(end -0.67945 -0.305054)
			(stroke
				(width 0.1)
				(type default)
			)
			(layer "F.Fab")
		)
		(fp_line
			(start -0.12065 -0.305054)
			(end -0.12065 -0.2794)
			(stroke
				(width 0.1)
				(type default)
			)
			(layer "F.Fab")
		)
		(fp_line
			(start -0.12065 -0.2794)
			(end 0.12065 -0.2794)
			(stroke
				(width 0.1)
				(type default)
			)
			(layer "F.Fab")
		)
		(fp_line
			(start -0.12065 0.2794)
			(end -0.12065 0.3048)
			(stroke
				(width 0.1)
				(type default)
			)
			(layer "F.Fab")
		)
		(fp_line
			(start -0.12065 0.3048)
			(end -0.67945 0.3048)
			(stroke
				(width 0.1)
				(type default)
			)
			(layer "F.Fab")
		)
		(fp_line
			(start 0.120396 0.2794)
			(end -0.12065 0.2794)
			(stroke
				(width 0.1)
				(type default)
			)
			(layer "F.Fab")
		)
		(fp_line
			(start 0.120396 0.3048)
			(end 0.120396 0.2794)
			(stroke
				(width 0.1)
				(type default)
			)
			(layer "F.Fab")
		)
		(fp_line
			(start 0.12065 -0.3048)
			(end 0.67945 -0.3048)
			(stroke
				(width 0.1)
				(type default)
			)
			(layer "F.Fab")
		)
		(fp_line
			(start 0.12065 -0.2794)
			(end 0.12065 -0.3048)
			(stroke
				(width 0.1)
				(type default)
			)
			(layer "F.Fab")
		)
		(fp_line
			(start 0.67945 -0.3048)
			(end 0.67945 0.3048)
			(stroke
				(width 0.1)
				(type default)
			)
			(layer "F.Fab")
		)
		(fp_line
			(start 0.67945 0.3048)
			(end 0.120396 0.3048)
			(stroke
				(width 0.1)
				(type default)
			)
			(layer "F.Fab")
		)
		(pad "1" smd circle
			(at -0.40005 0)
			(size 0 0)
			(layers "F.Cu" "F.Mask" "F.Paste")
			(net "PVCCIN_CPU0_LSET4")
		)
		(pad "2" smd circle
			(at 0.40005 0)
			(size 0 0)
			(layers "F.Cu" "F.Mask" "F.Paste")
			(net "GND")
		)
	)
	(footprint ""
		(layer "F.Cu")
		(at 203.1492 -95.91802 90)
		(property "Reference" "U339"
			(at -0.8382 2.13487 90)
			(unlocked yes)
			(layer "F.SilkS")
			(effects
				(font
					(size 0.7874 0.5842)
					(thickness 0.1524)
				)
			)
		)
		(property "Value" ""
			(at 0 0 90)
			(layer "F.Fab")
			(effects
				(font
					(size 1.27 1.27)
				)
			)
		)
		(duplicate_pad_numbers_are_jumpers no)
		(fp_line
			(start 2.032 -1.549908)
			(end 2.032 1.549908)
			(stroke
				(width 0.1524)
				(type default)
			)
			(layer "F.SilkS")
		)
		(fp_line
			(start 0.508 -1.549908)
			(end 2.032 -1.549908)
			(stroke
				(width 0.1524)
				(type default)
			)
			(layer "F.SilkS")
		)
		(fp_line
			(start -0.508 -1.549908)
			(end 0 -0.762)
			(stroke
				(width 0.1524)
				(type default)
			)
			(layer "F.SilkS")
		)
		(fp_line
			(start -2.032 -1.549908)
			(end -0.508 -1.549908)
			(stroke
				(width 0.1524)
				(type default)
			)
			(layer "F.SilkS")
		)
		(fp_line
			(start 0 -0.762)
			(end 0.508 -1.549908)
			(stroke
				(width 0.1524)
				(type default)
			)
			(layer "F.SilkS")
		)
		(fp_line
			(start 2.032 1.549908)
			(end -2.032 1.549908)
			(stroke
				(width 0.1524)
				(type default)
			)
			(layer "F.SilkS")
		)
		(fp_line
			(start -2.032 1.549908)
			(end -2.032 -1.549908)
			(stroke
				(width 0.1524)
				(type default)
			)
			(layer "F.SilkS")
		)
		(fp_poly
			(pts
				(xy -3.2004 -1.45796) (xy -3.2004 -0.44196) (xy -2.1844 -0.94996)
			)
			(stroke
				(width 0)
				(type default)
			)
			(fill yes)
			(layer "F.SilkS")
		)
		(fp_line
			(start 0.849884 -1.549908)
			(end 0.849884 1.549908)
			(stroke
				(width 0.1)
				(type default)
			)
			(layer "F.Fab")
		)
		(fp_line
			(start -0.849884 -1.549908)
			(end 0.849884 -1.549908)
			(stroke
				(width 0.1)
				(type default)
			)
			(layer "F.Fab")
		)
		(fp_line
			(start 0.849884 1.549908)
			(end -0.849884 1.549908)
			(stroke
				(width 0.1)
				(type default)
			)
			(layer "F.Fab")
		)
		(fp_line
			(start -0.849884 1.549908)
			(end -0.849884 -1.549908)
			(stroke
				(width 0.1)
				(type default)
			)
			(layer "F.Fab")
		)
		(fp_poly
			(pts
				(xy -3.2004 -1.45796) (xy -3.2004 -0.44196) (xy -2.1844 -0.94996)
			)
			(stroke
				(width 0)
				(type default)
			)
			(fill yes)
			(layer "F.Fab")
		)
		(pad "1" smd rect
			(at -1.35001 -0.94996)
			(size 0.6096 1.0668)
			(layers "F.Cu" "F.Mask" "F.Paste")
			(net "UV_ADR_P2V5_COMP")
		)
		(pad "2" smd rect
			(at -1.35001 0)
			(size 0.6096 1.0668)
			(layers "F.Cu" "F.Mask" "F.Paste")
			(net "GND")
		)
		(pad "3" smd rect
			(at -1.35001 0.94996)
			(size 0.6096 1.0668)
			(layers "F.Cu" "F.Mask" "F.Paste")
			(net "P12V_AUX_UV_ADR_TRIGGER")
		)
		(pad "4" smd rect
			(at 1.35001 0.94996)
			(size 0.6096 1.0668)
			(layers "F.Cu" "F.Mask" "F.Paste")
			(net "FM_UV_ADR_TRIGGER_N_R2")
		)
		(pad "5" smd rect
			(at 1.35001 -0.94996)
			(size 0.6096 1.0668)
			(layers "F.Cu" "F.Mask" "F.Paste")
			(net "P12V_AUX")
		)
	)
	(footprint ""
		(layer "F.Cu")
		(at 36.795202 -180.55336)
		(property "Reference" "PC1286"
			(at 0 0 0)
			(layer "F.SilkS")
			(hide yes)
			(effects
				(font
					(size 1.27 1.27)
				)
			)
		)
		(property "Value" ""
			(at 0 0 0)
			(layer "F.Fab")
			(effects
				(font
					(size 1.27 1.27)
				)
			)
		)
		(duplicate_pad_numbers_are_jumpers no)
		(fp_line
			(start -1.524 -0.762)
			(end 1.524 -0.762)
			(stroke
				(width 0.1524)
				(type default)
			)
			(layer "F.SilkS")
		)
		(fp_line
			(start -1.524 0.762)
			(end -1.524 -0.762)
			(stroke
				(width 0.1524)
				(type default)
			)
			(layer "F.SilkS")
		)
		(fp_line
			(start 1.524 -0.762)
			(end 1.524 0.762)
			(stroke
				(width 0.1524)
				(type default)
			)
			(layer "F.SilkS")
		)
		(fp_line
			(start 1.524 0.762)
			(end -1.524 0.762)
			(stroke
				(width 0.1524)
				(type default)
			)
			(layer "F.SilkS")
		)
		(fp_line
			(start -1.1049 -0.724916)
			(end -1.1049 0.724916)
			(stroke
				(width 0.1)
				(type default)
			)
			(layer "F.Fab")
		)
		(fp_line
			(start -1.1049 0.724916)
			(end 1.1049 0.724916)
			(stroke
				(width 0.1)
				(type default)
			)
			(layer "F.Fab")
		)
		(fp_line
			(start 1.1049 -0.724916)
			(end -1.1049 -0.724916)
			(stroke
				(width 0.1)
				(type default)
			)
			(layer "F.Fab")
		)
		(fp_line
			(start 1.1049 0.724916)
			(end 1.1049 -0.724916)
			(stroke
				(width 0.1)
				(type default)
			)
			(layer "F.Fab")
		)
		(pad "1" smd rect
			(at -0.889 0 180)
			(size 1.016 1.27)
			(layers "F.Cu" "F.Mask" "F.Paste")
			(net "PVNN_MAIN_CPU1")
		)
		(pad "2" smd rect
			(at 0.889 0 180)
			(size 1.016 1.27)
			(layers "F.Cu" "F.Mask" "F.Paste")
			(net "GND")
		)
	)
	(footprint ""
		(layer "F.Cu")
		(at 361.25658 -407.228548)
		(property "Reference" "C2341"
			(at 0 0 0)
			(layer "F.SilkS")
			(hide yes)
			(effects
				(font
					(size 1.27 1.27)
				)
			)
		)
		(property "Value" ""
			(at 0 0 0)
			(layer "F.Fab")
			(effects
				(font
					(size 1.27 1.27)
				)
			)
		)
		(duplicate_pad_numbers_are_jumpers no)
		(fp_line
			(start -0.7874 -0.4064)
			(end 0.7874 -0.4064)
			(stroke
				(width 0.1524)
				(type default)
			)
			(layer "F.SilkS")
		)
		(fp_line
			(start -0.7874 0.4064)
			(end -0.7874 -0.4064)
			(stroke
				(width 0.1524)
				(type default)
			)
			(layer "F.SilkS")
		)
		(fp_line
			(start 0.7874 -0.4064)
			(end 0.7874 0.4064)
			(stroke
				(width 0.1524)
				(type default)
			)
			(layer "F.SilkS")
		)
		(fp_line
			(start 0.7874 0.4064)
			(end -0.7874 0.4064)
			(stroke
				(width 0.1524)
				(type default)
			)
			(layer "F.SilkS")
		)
		(fp_line
			(start -0.67945 -0.305054)
			(end -0.12065 -0.305054)
			(stroke
				(width 0.1)
				(type default)
			)
			(layer "F.Fab")
		)
		(fp_line
			(start -0.67945 0.3048)
			(end -0.67945 -0.305054)
			(stroke
				(width 0.1)
				(type default)
			)
			(layer "F.Fab")
		)
		(fp_line
			(start -0.12065 -0.305054)
			(end -0.12065 -0.2794)
			(stroke
				(width 0.1)
				(type default)
			)
			(layer "F.Fab")
		)
		(fp_line
			(start -0.12065 -0.2794)
			(end 0.12065 -0.2794)
			(stroke
				(width 0.1)
				(type default)
			)
			(layer "F.Fab")
		)
		(fp_line
			(start -0.12065 0.2794)
			(end -0.12065 0.3048)
			(stroke
				(width 0.1)
				(type default)
			)
			(layer "F.Fab")
		)
		(fp_line
			(start -0.12065 0.3048)
			(end -0.67945 0.3048)
			(stroke
				(width 0.1)
				(type default)
			)
			(layer "F.Fab")
		)
		(fp_line
			(start 0.120396 0.2794)
			(end -0.12065 0.2794)
			(stroke
				(width 0.1)
				(type default)
			)
			(layer "F.Fab")
		)
		(fp_line
			(start 0.120396 0.3048)
			(end 0.120396 0.2794)
			(stroke
				(width 0.1)
				(type default)
			)
			(layer "F.Fab")
		)
		(fp_line
			(start 0.12065 -0.3048)
			(end 0.67945 -0.3048)
			(stroke
				(width 0.1)
				(type default)
			)
			(layer "F.Fab")
		)
		(fp_line
			(start 0.12065 -0.2794)
			(end 0.12065 -0.3048)
			(stroke
				(width 0.1)
				(type default)
			)
			(layer "F.Fab")
		)
		(fp_line
			(start 0.67945 -0.3048)
			(end 0.67945 0.3048)
			(stroke
				(width 0.1)
				(type default)
			)
			(layer "F.Fab")
		)
		(fp_line
			(start 0.67945 0.3048)
			(end 0.120396 0.3048)
			(stroke
				(width 0.1)
				(type default)
			)
			(layer "F.Fab")
		)
		(pad "1" smd circle
			(at -0.40005 0)
			(size 0 0)
			(layers "F.Cu" "F.Mask" "F.Paste")
			(net "P3V3_AUX")
		)
		(pad "2" smd circle
			(at 0.40005 0)
			(size 0 0)
			(layers "F.Cu" "F.Mask" "F.Paste")
			(net "GND")
		)
	)
)
